# T6G (Grand Teton) — schematic netlist excerpt (pin names and nets, part order shuffled) for the footprints in the layout excerpt that follows; sources: Cadence DE-HDL packaged netlist, KiCad conversion of 04192023_DAF0TMB3IC0_F0TG_MB_C_brd_V02_OCP.brd

R4639  Q_RES  243 1% CHIP  pkg 1206LF  page 188 : A = P5V ; B = VR_P5V_EN_D
C299  Q_CAP  10PF 50V 5% EMPTY  pkg 0402  page 193 : A = SVID_PVDDCR_CPU0_P0_SVD_R ; B = GND
R151  Q_RES  0 5% CHIP  pkg 0402LF  page 160 : A = SMB_CPU0_CPU1_APML_SCL ; B = SMB_CPU0_CPU1_APML_BUF2_SCL

(kicad_pcb
	(version 20260206)
	(generator "pcbnew")
	(generator_version "10.0")
	(general
		(thickness 1.6)
		(legacy_teardrops no)
	)
	(paper "A4")
	(title_block
		(title "04192023_DAF0TMB3IC0_F0TG_MB_C_brd_V02_OCP.brd")
		(comment 1 "Grand Teton / footprints 7023-7025 of 8354")
	)
	(layers
		(0 "F.Cu" signal "TOP")
		(4 "In1.Cu" signal "GND")
		(6 "In2.Cu" signal "IN1")
		(8 "In3.Cu" signal "GND1")
		(10 "In4.Cu" signal "IN2")
		(12 "In5.Cu" signal "GND2")
		(14 "In6.Cu" signal "IN3")
		(16 "In7.Cu" signal "GND3")
		(18 "In8.Cu" signal "VCC")
		(20 "In9.Cu" signal "VCC1")
		(22 "In10.Cu" signal "GND4")
		(24 "In11.Cu" signal "IN4")
		(26 "In12.Cu" signal "GND5")
		(28 "In13.Cu" signal "IN5")
		(30 "In14.Cu" signal "GND6")
		(32 "In15.Cu" signal "IN6")
		(34 "In16.Cu" signal "GND7")
		(2 "B.Cu" signal "BOTTOM")
		(9 "F.Adhes" user "F.Adhesive")
		(11 "B.Adhes" user "B.Adhesive")
		(13 "F.Paste" user "Package Geometry/Pastemask Top")
		(15 "B.Paste" user "Package Geometry/Pastemask Bottom")
		(5 "F.SilkS" user "Ref Des/Silkscreen Top")
		(7 "B.SilkS" user "Ref Des/Silkscreen Bottom")
		(1 "F.Mask" user "Board Geometry/Soldermask Top")
		(3 "B.Mask" user "Board Geometry/Soldermask Bottom")
		(17 "Dwgs.User" user "User.Drawings")
		(19 "Cmts.User" user "User.Comments")
		(21 "Eco1.User" user "User.Eco1")
		(23 "Eco2.User" user "User.Eco2")
		(25 "Edge.Cuts" user "Board Geometry/Outline")
		(27 "Margin" user)
		(31 "F.CrtYd" user "Package Geometry/Place Bound Top")
		(29 "B.CrtYd" user "Package Geometry/Place Bound Bottom")
		(35 "F.Fab" user "Ref Des/Assembly Top")
		(33 "B.Fab" user "Ref Des/Assembly Bottom")
	)
	(footprint ""
		(layer "B.Cu")
		(at 233.68 -226.822)
		(property "Reference" "R151"
			(at 0 0 0)
			(layer "B.SilkS")
			(hide yes)
			(effects
				(font
					(size 1.27 1.27)
				)
				(justify mirror)
			)
		)
		(property "Value" ""
			(at 0 0 0)
			(layer "B.Fab")
			(effects
				(font
					(size 1.27 1.27)
				)
				(justify mirror)
			)
		)
		(duplicate_pad_numbers_are_jumpers no)
		(fp_line
			(start -0.7874 -0.4064)
			(end -0.7874 0.4064)
			(stroke
				(width 0.1524)
				(type default)
			)
			(layer "B.SilkS")
		)
		(fp_line
			(start -0.7874 0.4064)
			(end 0.7874 0.4064)
			(stroke
				(width 0.1524)
				(type default)
			)
			(layer "B.SilkS")
		)
		(fp_line
			(start 0.7874 -0.4064)
			(end -0.7874 -0.4064)
			(stroke
				(width 0.1524)
				(type default)
			)
			(layer "B.SilkS")
		)
		(fp_line
			(start 0.7874 0.4064)
			(end 0.7874 -0.4064)
			(stroke
				(width 0.1524)
				(type default)
			)
			(layer "B.SilkS")
		)
		(fp_line
			(start -0.67945 -0.3048)
			(end -0.67945 0.3048)
			(stroke
				(width 0.1)
				(type default)
			)
			(layer "B.Fab")
		)
		(fp_line
			(start -0.67945 0.3048)
			(end -0.120396 0.3048)
			(stroke
				(width 0.1)
				(type default)
			)
			(layer "B.Fab")
		)
		(fp_line
			(start -0.12065 -0.3048)
			(end -0.67945 -0.3048)
			(stroke
				(width 0.1)
				(type default)
			)
			(layer "B.Fab")
		)
		(fp_line
			(start -0.12065 -0.2794)
			(end -0.12065 -0.3048)
			(stroke
				(width 0.1)
				(type default)
			)
			(layer "B.Fab")
		)
		(fp_line
			(start -0.120396 0.2794)
			(end 0.12065 0.2794)
			(stroke
				(width 0.1)
				(type default)
			)
			(layer "B.Fab")
		)
		(fp_line
			(start -0.120396 0.3048)
			(end -0.120396 0.2794)
			(stroke
				(width 0.1)
				(type default)
			)
			(layer "B.Fab")
		)
		(fp_line
			(start 0.12065 -0.305054)
			(end 0.12065 -0.2794)
			(stroke
				(width 0.1)
				(type default)
			)
			(layer "B.Fab")
		)
		(fp_line
			(start 0.12065 -0.2794)
			(end -0.12065 -0.2794)
			(stroke
				(width 0.1)
				(type default)
			)
			(layer "B.Fab")
		)
		(fp_line
			(start 0.12065 0.2794)
			(end 0.12065 0.3048)
			(stroke
				(width 0.1)
				(type default)
			)
			(layer "B.Fab")
		)
		(fp_line
			(start 0.12065 0.3048)
			(end 0.67945 0.3048)
			(stroke
				(width 0.1)
				(type default)
			)
			(layer "B.Fab")
		)
		(fp_line
			(start 0.67945 -0.305054)
			(end 0.12065 -0.305054)
			(stroke
				(width 0.1)
				(type default)
			)
			(layer "B.Fab")
		)
		(fp_line
			(start 0.67945 0.3048)
			(end 0.67945 -0.305054)
			(stroke
				(width 0.1)
				(type default)
			)
			(layer "B.Fab")
		)
		(pad "1" smd rect
			(at 0.40005 0)
			(size 0.4572 0.508)
			(layers "B.Cu" "B.Mask" "B.Paste")
			(net "SMB_CPU0_CPU1_APML_SCL")
		)
		(pad "2" smd rect
			(at -0.40005 0)
			(size 0.4572 0.508)
			(layers "B.Cu" "B.Mask" "B.Paste")
			(net "SMB_CPU0_CPU1_APML_BUF2_SCL")
		)
	)
	(footprint ""
		(layer "B.Cu")
		(at 370.905278 -144.520158)
		(property "Reference" "C299"
			(at 0 0 0)
			(layer "B.SilkS")
			(hide yes)
			(effects
				(font
					(size 1.27 1.27)
				)
				(justify mirror)
			)
		)
		(property "Value" ""
			(at 0 0 0)
			(layer "B.Fab")
			(effects
				(font
					(size 1.27 1.27)
				)
				(justify mirror)
			)
		)
		(duplicate_pad_numbers_are_jumpers no)
		(fp_line
			(start -0.7874 -0.4064)
			(end -0.7874 0.4064)
			(stroke
				(width 0.1524)
				(type default)
			)
			(layer "B.SilkS")
		)
		(fp_line
			(start -0.7874 0.4064)
			(end 0.7874 0.4064)
			(stroke
				(width 0.1524)
				(type default)
			)
			(layer "B.SilkS")
		)
		(fp_line
			(start 0.7874 -0.4064)
			(end -0.7874 -0.4064)
			(stroke
				(width 0.1524)
				(type default)
			)
			(layer "B.SilkS")
		)
		(fp_line
			(start 0.7874 0.4064)
			(end 0.7874 -0.4064)
			(stroke
				(width 0.1524)
				(type default)
			)
			(layer "B.SilkS")
		)
		(fp_line
			(start -0.67945 -0.3048)
			(end -0.67945 0.3048)
			(stroke
				(width 0.1)
				(type default)
			)
			(layer "B.Fab")
		)
		(fp_line
			(start -0.67945 0.3048)
			(end -0.120396 0.3048)
			(stroke
				(width 0.1)
				(type default)
			)
			(layer "B.Fab")
		)
		(fp_line
			(start -0.12065 -0.3048)
			(end -0.67945 -0.3048)
			(stroke
				(width 0.1)
				(type default)
			)
			(layer "B.Fab")
		)
		(fp_line
			(start -0.12065 -0.2794)
			(end -0.12065 -0.3048)
			(stroke
				(width 0.1)
				(type default)
			)
			(layer "B.Fab")
		)
		(fp_line
			(start -0.120396 0.2794)
			(end 0.12065 0.2794)
			(stroke
				(width 0.1)
				(type default)
			)
			(layer "B.Fab")
		)
		(fp_line
			(start -0.120396 0.3048)
			(end -0.120396 0.2794)
			(stroke
				(width 0.1)
				(type default)
			)
			(layer "B.Fab")
		)
		(fp_line
			(start 0.12065 -0.305054)
			(end 0.12065 -0.2794)
			(stroke
				(width 0.1)
				(type default)
			)
			(layer "B.Fab")
		)
		(fp_line
			(start 0.12065 -0.2794)
			(end -0.12065 -0.2794)
			(stroke
				(width 0.1)
				(type default)
			)
			(layer "B.Fab")
		)
		(fp_line
			(start 0.12065 0.2794)
			(end 0.12065 0.3048)
			(stroke
				(width 0.1)
				(type default)
			)
			(layer "B.Fab")
		)
		(fp_line
			(start 0.12065 0.3048)
			(end 0.67945 0.3048)
			(stroke
				(width 0.1)
				(type default)
			)
			(layer "B.Fab")
		)
		(fp_line
			(start 0.67945 -0.305054)
			(end 0.12065 -0.305054)
			(stroke
				(width 0.1)
				(type default)
			)
			(layer "B.Fab")
		)
		(fp_line
			(start 0.67945 0.3048)
			(end 0.67945 -0.305054)
			(stroke
				(width 0.1)
				(type default)
			)
			(layer "B.Fab")
		)
		(pad "1" smd circle
			(at 0.40005 0 180)
			(size 0 0)
			(layers "B.Cu" "B.Mask" "B.Paste")
			(net "SVID_PVDDCR_CPU0_P0_SVD_R")
		)
		(pad "2" smd circle
			(at -0.40005 0 180)
			(size 0 0)
			(layers "B.Cu" "B.Mask" "B.Paste")
			(net "GND")
		)
	)
	(footprint ""
		(layer "B.Cu")
		(at 404.574502 -152.29078 -90)
		(property "Reference" "R4639"
			(at 0 0 90)
			(layer "B.SilkS")
			(hide yes)
			(effects
				(font
					(size 1.27 1.27)
				)
				(justify mirror)
			)
		)
		(property "Value" ""
			(at 0 0 90)
			(layer "B.Fab")
			(effects
				(font
					(size 1.27 1.27)
				)
				(justify mirror)
			)
		)
		(duplicate_pad_numbers_are_jumpers no)
		(fp_line
			(start -2.234946 0.9271)
			(end 2.234946 0.9271)
			(stroke
				(width 0.1524)
				(type default)
			)
			(layer "B.SilkS")
		)
		(fp_line
			(start 2.234946 0.9271)
			(end 2.234946 -0.9271)
			(stroke
				(width 0.1524)
				(type default)
			)
			(layer "B.SilkS")
		)
		(fp_line
			(start -2.234946 -0.9271)
			(end -2.234946 0.9271)
			(stroke
				(width 0.1524)
				(type default)
			)
			(layer "B.SilkS")
		)
		(fp_line
			(start 2.234946 -0.9271)
			(end -2.234946 -0.9271)
			(stroke
				(width 0.1524)
				(type default)
			)
			(layer "B.SilkS")
		)
		(fp_line
			(start -1.575054 0.824992)
			(end -1.575054 -0.824992)
			(stroke
				(width 0.1)
				(type default)
			)
			(layer "B.Fab")
		)
		(fp_line
			(start 1.575054 0.824992)
			(end -1.575054 0.824992)
			(stroke
				(width 0.1)
				(type default)
			)
			(layer "B.Fab")
		)
		(fp_line
			(start -1.575054 -0.824992)
			(end 1.575054 -0.824992)
			(stroke
				(width 0.1)
				(type default)
			)
			(layer "B.Fab")
		)
		(fp_line
			(start 1.575054 -0.824992)
			(end 1.575054 0.824992)
			(stroke
				(width 0.1)
				(type default)
			)
			(layer "B.Fab")
		)
		(pad "1" smd rect
			(at 1.599946 0 90)
			(size 1.016 1.6002)
			(layers "B.Cu" "B.Mask" "B.Paste")
			(net "P5V")
		)
		(pad "2" smd rect
			(at -1.599946 0 90)
			(size 1.016 1.6002)
			(layers "B.Cu" "B.Mask" "B.Paste")
			(net "VR_P5V_EN_D")
		)
	)
)
